(kicad_pcb
	(version 20260206)
	(generator "pcbnew")
	(generator_version "10.0")
	(general
		(thickness 1.6)
		(legacy_teardrops no)
	)
	(paper "A4")
	(title_block
		(title "03242023_DA0F0TMBIJ0_F0T_Motherboard_J_brd_V01_OCP.brd")
		(comment 1 "Grand Teton / footprints 2875-2880 of 6105")
	)
	(layers
		(0 "F.Cu" signal "TOP")
		(4 "In1.Cu" signal "GND")
		(6 "In2.Cu" signal "IN1")
		(8 "In3.Cu" signal "GND1")
		(10 "In4.Cu" signal "IN2")
		(12 "In5.Cu" signal "GND2")
		(14 "In6.Cu" signal "IN3")
		(16 "In7.Cu" signal "GND3")
		(18 "In8.Cu" signal "VCC")
		(20 "In9.Cu" signal "VCC1")
		(22 "In10.Cu" signal "GND4")
		(24 "In11.Cu" signal "IN4")
		(26 "In12.Cu" signal "GND5")
		(28 "In13.Cu" signal "IN5")
		(30 "In14.Cu" signal "GND6")
		(32 "In15.Cu" signal "IN6")
		(34 "In16.Cu" signal "GND7")
		(2 "B.Cu" signal "BOTTOM")
		(9 "F.Adhes" user "F.Adhesive")
		(11 "B.Adhes" user "B.Adhesive")
		(13 "F.Paste" user "Package Geometry/Pastemask Top")
		(15 "B.Paste" user "Package Geometry/Pastemask Bottom")
		(5 "F.SilkS" user "Ref Des/Silkscreen Top")
		(7 "B.SilkS" user "Ref Des/Silkscreen Bottom")
		(1 "F.Mask" user "Board Geometry/Soldermask Top")
		(3 "B.Mask" user "Board Geometry/Soldermask Bottom")
		(17 "Dwgs.User" user "User.Drawings")
		(19 "Cmts.User" user "User.Comments")
		(21 "Eco1.User" user "User.Eco1")
		(23 "Eco2.User" user "User.Eco2")
		(25 "Edge.Cuts" user "Board Geometry/Outline")
		(27 "Margin" user)
		(31 "F.CrtYd" user "Package Geometry/Place Bound Top")
		(29 "B.CrtYd" user "Package Geometry/Place Bound Bottom")
		(35 "F.Fab" user "Ref Des/Assembly Top")
		(33 "B.Fab" user "Ref Des/Assembly Bottom")
	)
	(footprint ""
		(layer "F.Cu")
		(at 201.00036 -118.074948)
		(property "Reference" "R1470"
			(at 0 0 0)
			(layer "F.SilkS")
			(hide yes)
			(effects
				(font
					(size 1.27 1.27)
				)
			)
		)
		(property "Value" ""
			(at 0 0 0)
			(layer "F.Fab")
			(effects
				(font
					(size 1.27 1.27)
				)
			)
		)
		(duplicate_pad_numbers_are_jumpers no)
		(fp_line
			(start -0.7874 -0.4064)
			(end 0.7874 -0.4064)
			(stroke
				(width 0.1524)
				(type default)
			)
			(layer "F.SilkS")
		)
		(fp_line
			(start -0.7874 0.4064)
			(end -0.7874 -0.4064)
			(stroke
				(width 0.1524)
				(type default)
			)
			(layer "F.SilkS")
		)
		(fp_line
			(start 0.7874 -0.4064)
			(end 0.7874 0.4064)
			(stroke
				(width 0.1524)
				(type default)
			)
			(layer "F.SilkS")
		)
		(fp_line
			(start 0.7874 0.4064)
			(end -0.7874 0.4064)
			(stroke
				(width 0.1524)
				(type default)
			)
			(layer "F.SilkS")
		)
		(fp_line
			(start -0.67945 -0.305054)
			(end -0.12065 -0.305054)
			(stroke
				(width 0.1)
				(type default)
			)
			(layer "F.Fab")
		)
		(fp_line
			(start -0.67945 0.3048)
			(end -0.67945 -0.305054)
			(stroke
				(width 0.1)
				(type default)
			)
			(layer "F.Fab")
		)
		(fp_line
			(start -0.12065 -0.305054)
			(end -0.12065 -0.2794)
			(stroke
				(width 0.1)
				(type default)
			)
			(layer "F.Fab")
		)
		(fp_line
			(start -0.12065 -0.2794)
			(end 0.12065 -0.2794)
			(stroke
				(width 0.1)
				(type default)
			)
			(layer "F.Fab")
		)
		(fp_line
			(start -0.12065 0.2794)
			(end -0.12065 0.3048)
			(stroke
				(width 0.1)
				(type default)
			)
			(layer "F.Fab")
		)
		(fp_line
			(start -0.12065 0.3048)
			(end -0.67945 0.3048)
			(stroke
				(width 0.1)
				(type default)
			)
			(layer "F.Fab")
		)
		(fp_line
			(start 0.120396 0.2794)
			(end -0.12065 0.2794)
			(stroke
				(width 0.1)
				(type default)
			)
			(layer "F.Fab")
		)
		(fp_line
			(start 0.120396 0.3048)
			(end 0.120396 0.2794)
			(stroke
				(width 0.1)
				(type default)
			)
			(layer "F.Fab")
		)
		(fp_line
			(start 0.12065 -0.3048)
			(end 0.67945 -0.3048)
			(stroke
				(width 0.1)
				(type default)
			)
			(layer "F.Fab")
		)
		(fp_line
			(start 0.12065 -0.2794)
			(end 0.12065 -0.3048)
			(stroke
				(width 0.1)
				(type default)
			)
			(layer "F.Fab")
		)
		(fp_line
			(start 0.67945 -0.3048)
			(end 0.67945 0.3048)
			(stroke
				(width 0.1)
				(type default)
			)
			(layer "F.Fab")
		)
		(fp_line
			(start 0.67945 0.3048)
			(end 0.120396 0.3048)
			(stroke
				(width 0.1)
				(type default)
			)
			(layer "F.Fab")
		)
		(pad "1" smd circle
			(at -0.40005 0)
			(size 0 0)
			(layers "F.Cu" "F.Mask" "F.Paste")
			(net "RST_PLTRST_PLD_B_N")
		)
		(pad "2" smd circle
			(at 0.40005 0)
			(size 0 0)
			(layers "F.Cu" "F.Mask" "F.Paste")
			(net "RST_PLTRST_B_MUX_N")
		)
	)
	(footprint ""
		(layer "F.Cu")
		(at 239.152684 -58.32729 180)
		(property "Reference" "C1989"
			(at 0 0 180)
			(layer "F.SilkS")
			(hide yes)
			(effects
				(font
					(size 1.27 1.27)
				)
			)
		)
		(property "Value" ""
			(at 0 0 180)
			(layer "F.Fab")
			(effects
				(font
					(size 1.27 1.27)
				)
			)
		)
		(duplicate_pad_numbers_are_jumpers no)
		(fp_line
			(start 0.299974 0.150114)
			(end -0.299974 0.150114)
			(stroke
				(width 0.1)
				(type default)
			)
			(layer "F.Fab")
		)
		(fp_line
			(start 0.299974 -0.150114)
			(end 0.299974 0.150114)
			(stroke
				(width 0.1)
				(type default)
			)
			(layer "F.Fab")
		)
		(fp_line
			(start -0.299974 0.150114)
			(end -0.299974 -0.150114)
			(stroke
				(width 0.1)
				(type default)
			)
			(layer "F.Fab")
		)
		(fp_line
			(start -0.299974 -0.150114)
			(end 0.299974 -0.150114)
			(stroke
				(width 0.1)
				(type default)
			)
			(layer "F.Fab")
		)
		(pad "1" smd rect
			(at -0.2667 0 180)
			(size 0.3048 0.381)
			(layers "F.Cu" "F.Mask" "F.Paste")
			(net "P3E_PCH_E1S_TX_DP<3>")
		)
		(pad "2" smd rect
			(at 0.2667 0 180)
			(size 0.3048 0.381)
			(layers "F.Cu" "F.Mask" "F.Paste")
			(net "P3E_PCH_E1S_TX_C_DP<3>")
		)
		(zone
			(layer "In1.Cu")
			(hatch none 0.5)
			(connect_pads
				(clearance 0)
			)
			(min_thickness 0.25)
			(keepout
				(tracks not_allowed)
				(vias allowed)
				(pads allowed)
				(copperpour not_allowed)
				(footprints allowed)
			)
			(placement
				(enabled no)
				(sheetname "")
			)
			(fill
				(thermal_gap 0.5)
				(thermal_bridge_width 0.5)
				(island_removal_mode 0)
			)
			(polygon
				(pts
					(arc
						(start 239.012984 -58.567574)
						(mid 239.066866 -58.545256)
						(end 239.089184 -58.491374)
					)
					(arc
						(start 239.089184 -58.161174)
						(mid 239.066866 -58.107292)
						(end 239.012984 -58.084974)
					)
					(arc
						(start 238.758984 -58.084974)
						(mid 238.705102 -58.107292)
						(end 238.682784 -58.161174)
					)
					(arc
						(start 238.682784 -58.491374)
						(mid 238.705102 -58.545256)
						(end 238.758984 -58.567574)
					)
				)
			)
		)
		(zone
			(layer "In1.Cu")
			(hatch none 0.5)
			(connect_pads
				(clearance 0)
			)
			(min_thickness 0.25)
			(keepout
				(tracks not_allowed)
				(vias allowed)
				(pads allowed)
				(copperpour not_allowed)
				(footprints allowed)
			)
			(placement
				(enabled no)
				(sheetname "")
			)
			(fill
				(thermal_gap 0.5)
				(thermal_bridge_width 0.5)
				(island_removal_mode 0)
			)
			(polygon
				(pts
					(arc
						(start 239.546384 -58.567574)
						(mid 239.600266 -58.545256)
						(end 239.622584 -58.491374)
					)
					(arc
						(start 239.622584 -58.161174)
						(mid 239.600266 -58.107292)
						(end 239.546384 -58.084974)
					)
					(arc
						(start 239.292384 -58.084974)
						(mid 239.238502 -58.107292)
						(end 239.216184 -58.161174)
					)
					(arc
						(start 239.216184 -58.491374)
						(mid 239.238502 -58.545256)
						(end 239.292384 -58.567574)
					)
				)
			)
		)
	)
	(footprint ""
		(layer "F.Cu")
		(at 29.954728 -153.76652)
		(property "Reference" "H126"
			(at -10.20572 0.41783 0)
			(unlocked yes)
			(layer "F.SilkS")
			(effects
				(font
					(size 0.7874 0.5842)
					(thickness 0.1524)
				)
				(justify left)
			)
		)
		(property "Value" ""
			(at 0 0 0)
			(layer "F.Fab")
			(effects
				(font
					(size 1.27 1.27)
				)
			)
		)
		(duplicate_pad_numbers_are_jumpers no)
		(fp_circle
			(center 0 0)
			(end 5.8166 0)
			(stroke
				(width 0.1524)
				(type default)
			)
			(fill no)
			(layer "F.SilkS")
		)
		(fp_circle
			(center 0 0)
			(end 5.8166 0)
			(stroke
				(width 0.1524)
				(type default)
			)
			(fill no)
			(layer "B.SilkS")
		)
		(fp_circle
			(center 0 0)
			(end 5.8166 0)
			(stroke
				(width 0.1)
				(type default)
			)
			(fill no)
			(layer "B.Fab")
		)
		(fp_circle
			(center 0 0)
			(end 5.8166 0)
			(stroke
				(width 0.1)
				(type default)
			)
			(fill no)
			(layer "F.Fab")
		)
		(pad "" np_thru_hole circle
			(at 0 0)
			(size 10.0076 10.0076)
			(drill 10.0076)
			(layers "*.Cu" "*.Mask")
			(clearance 0.381)
			(thermal_gap 0.381)
		)
	)
	(footprint ""
		(layer "F.Cu")
		(at 355.228144 -240.276888 90)
		(property "Reference" "C1035"
			(at 0 0 90)
			(layer "F.SilkS")
			(hide yes)
			(effects
				(font
					(size 1.27 1.27)
				)
			)
		)
		(property "Value" ""
			(at 0 0 90)
			(layer "F.Fab")
			(effects
				(font
					(size 1.27 1.27)
				)
			)
		)
		(duplicate_pad_numbers_are_jumpers no)
		(fp_line
			(start 0.7874 -0.4064)
			(end 0.7874 0.4064)
			(stroke
				(width 0.1524)
				(type default)
			)
			(layer "F.SilkS")
		)
		(fp_line
			(start -0.7874 -0.4064)
			(end 0.7874 -0.4064)
			(stroke
				(width 0.1524)
				(type default)
			)
			(layer "F.SilkS")
		)
		(fp_line
			(start 0.7874 0.4064)
			(end -0.7874 0.4064)
			(stroke
				(width 0.1524)
				(type default)
			)
			(layer "F.SilkS")
		)
		(fp_line
			(start -0.7874 0.4064)
			(end -0.7874 -0.4064)
			(stroke
				(width 0.1524)
				(type default)
			)
			(layer "F.SilkS")
		)
		(fp_line
			(start -0.12065 -0.305054)
			(end -0.12065 -0.2794)
			(stroke
				(width 0.1)
				(type default)
			)
			(layer "F.Fab")
		)
		(fp_line
			(start -0.67945 -0.305054)
			(end -0.12065 -0.305054)
			(stroke
				(width 0.1)
				(type default)
			)
			(layer "F.Fab")
		)
		(fp_line
			(start 0.67945 -0.3048)
			(end 0.67945 0.3048)
			(stroke
				(width 0.1)
				(type default)
			)
			(layer "F.Fab")
		)
		(fp_line
			(start 0.12065 -0.3048)
			(end 0.67945 -0.3048)
			(stroke
				(width 0.1)
				(type default)
			)
			(layer "F.Fab")
		)
		(fp_line
			(start 0.12065 -0.2794)
			(end 0.12065 -0.3048)
			(stroke
				(width 0.1)
				(type default)
			)
			(layer "F.Fab")
		)
		(fp_line
			(start -0.12065 -0.2794)
			(end 0.12065 -0.2794)
			(stroke
				(width 0.1)
				(type default)
			)
			(layer "F.Fab")
		)
		(fp_line
			(start 0.120396 0.2794)
			(end -0.12065 0.2794)
			(stroke
				(width 0.1)
				(type default)
			)
			(layer "F.Fab")
		)
		(fp_line
			(start -0.12065 0.2794)
			(end -0.12065 0.3048)
			(stroke
				(width 0.1)
				(type default)
			)
			(layer "F.Fab")
		)
		(fp_line
			(start 0.67945 0.3048)
			(end 0.120396 0.3048)
			(stroke
				(width 0.1)
				(type default)
			)
			(layer "F.Fab")
		)
		(fp_line
			(start 0.120396 0.3048)
			(end 0.120396 0.2794)
			(stroke
				(width 0.1)
				(type default)
			)
			(layer "F.Fab")
		)
		(fp_line
			(start -0.12065 0.3048)
			(end -0.67945 0.3048)
			(stroke
				(width 0.1)
				(type default)
			)
			(layer "F.Fab")
		)
		(fp_line
			(start -0.67945 0.3048)
			(end -0.67945 -0.305054)
			(stroke
				(width 0.1)
				(type default)
			)
			(layer "F.Fab")
		)
		(pad "1" smd circle
			(at -0.40005 0 90)
			(size 0 0)
			(layers "F.Cu" "F.Mask" "F.Paste")
			(net "PVCCIN_CPU0")
		)
		(pad "2" smd circle
			(at 0.40005 0 90)
			(size 0 0)
			(layers "F.Cu" "F.Mask" "F.Paste")
			(net "GND")
		)
	)
	(footprint ""
		(layer "F.Cu")
		(at 353.88423 -338.180172 90)
		(property "Reference" "PR1786"
			(at 0 0 90)
			(layer "F.SilkS")
			(hide yes)
			(effects
				(font
					(size 1.27 1.27)
				)
			)
		)
		(property "Value" ""
			(at 0 0 90)
			(layer "F.Fab")
			(effects
				(font
					(size 1.27 1.27)
				)
			)
		)
		(duplicate_pad_numbers_are_jumpers no)
		(fp_line
			(start 0.7874 -0.4064)
			(end 0.7874 0.4064)
			(stroke
				(width 0.1524)
				(type default)
			)
			(layer "F.SilkS")
		)
		(fp_line
			(start -0.7874 -0.4064)
			(end 0.7874 -0.4064)
			(stroke
				(width 0.1524)
				(type default)
			)
			(layer "F.SilkS")
		)
		(fp_line
			(start 0.7874 0.4064)
			(end -0.7874 0.4064)
			(stroke
				(width 0.1524)
				(type default)
			)
			(layer "F.SilkS")
		)
		(fp_line
			(start -0.7874 0.4064)
			(end -0.7874 -0.4064)
			(stroke
				(width 0.1524)
				(type default)
			)
			(layer "F.SilkS")
		)
		(fp_line
			(start -0.12065 -0.305054)
			(end -0.12065 -0.2794)
			(stroke
				(width 0.1)
				(type default)
			)
			(layer "F.Fab")
		)
		(fp_line
			(start -0.67945 -0.305054)
			(end -0.12065 -0.305054)
			(stroke
				(width 0.1)
				(type default)
			)
			(layer "F.Fab")
		)
		(fp_line
			(start 0.67945 -0.3048)
			(end 0.67945 0.3048)
			(stroke
				(width 0.1)
				(type default)
			)
			(layer "F.Fab")
		)
		(fp_line
			(start 0.12065 -0.3048)
			(end 0.67945 -0.3048)
			(stroke
				(width 0.1)
				(type default)
			)
			(layer "F.Fab")
		)
		(fp_line
			(start 0.12065 -0.2794)
			(end 0.12065 -0.3048)
			(stroke
				(width 0.1)
				(type default)
			)
			(layer "F.Fab")
		)
		(fp_line
			(start -0.12065 -0.2794)
			(end 0.12065 -0.2794)
			(stroke
				(width 0.1)
				(type default)
			)
			(layer "F.Fab")
		)
		(fp_line
			(start 0.120396 0.2794)
			(end -0.12065 0.2794)
			(stroke
				(width 0.1)
				(type default)
			)
			(layer "F.Fab")
		)
		(fp_line
			(start -0.12065 0.2794)
			(end -0.12065 0.3048)
			(stroke
				(width 0.1)
				(type default)
			)
			(layer "F.Fab")
		)
		(fp_line
			(start 0.67945 0.3048)
			(end 0.120396 0.3048)
			(stroke
				(width 0.1)
				(type default)
			)
			(layer "F.Fab")
		)
		(fp_line
			(start 0.120396 0.3048)
			(end 0.120396 0.2794)
			(stroke
				(width 0.1)
				(type default)
			)
			(layer "F.Fab")
		)
		(fp_line
			(start -0.12065 0.3048)
			(end -0.67945 0.3048)
			(stroke
				(width 0.1)
				(type default)
			)
			(layer "F.Fab")
		)
		(fp_line
			(start -0.67945 0.3048)
			(end -0.67945 -0.305054)
			(stroke
				(width 0.1)
				(type default)
			)
			(layer "F.Fab")
		)
		(pad "1" smd circle
			(at -0.40005 0 90)
			(size 0 0)
			(layers "F.Cu" "F.Mask" "F.Paste")
			(net "SW_PVCCIN_CPU0_BOOT2")
		)
		(pad "2" smd circle
			(at 0.40005 0 90)
			(size 0 0)
			(layers "F.Cu" "F.Mask" "F.Paste")
			(net "SW_PVCCIN_CPU0_BOOT2_R")
		)
	)
	(footprint ""
		(layer "F.Cu")
		(at 215.259666 -54.455314)
		(property "Reference" "U276"
			(at 3.789934 1.423416 0)
			(unlocked yes)
			(layer "F.SilkS")
			(effects
				(font
					(size 0.7874 0.5842)
					(thickness 0.1524)
				)
			)
		)
		(property "Value" ""
			(at 0 0 0)
			(layer "F.Fab")
			(effects
				(font
					(size 1.27 1.27)
				)
			)
		)
		(duplicate_pad_numbers_are_jumpers no)
		(fp_line
			(start -1.500124 -1.500124)
			(end -1.004062 -1.500124)
			(stroke
				(width 0.1524)
				(type default)
			)
			(layer "F.SilkS")
		)
		(fp_line
			(start -1.500124 -1.004062)
			(end -1.500124 -1.500124)
			(stroke
				(width 0.1524)
				(type default)
			)
			(layer "F.SilkS")
		)
		(fp_line
			(start -1.500124 1.500124)
			(end -1.500124 1.004062)
			(stroke
				(width 0.1524)
				(type default)
			)
			(layer "F.SilkS")
		)
		(fp_line
			(start -1.004062 1.500124)
			(end -1.500124 1.500124)
			(stroke
				(width 0.1524)
				(type default)
			)
			(layer "F.SilkS")
		)
		(fp_line
			(start 1.004062 -1.500124)
			(end 1.500124 -1.500124)
			(stroke
				(width 0.1524)
				(type default)
			)
			(layer "F.SilkS")
		)
		(fp_line
			(start 1.500124 -1.500124)
			(end 1.500124 -1.004062)
			(stroke
				(width 0.1524)
				(type default)
			)
			(layer "F.SilkS")
		)
		(fp_line
			(start 1.500124 1.004062)
			(end 1.500124 1.500124)
			(stroke
				(width 0.1524)
				(type default)
			)
			(layer "F.SilkS")
		)
		(fp_line
			(start 1.500124 1.500124)
			(end 1.004062 1.500124)
			(stroke
				(width 0.1524)
				(type default)
			)
			(layer "F.SilkS")
		)
		(fp_poly
			(pts
				(xy -2.468626 -1.082294) (xy -1.783588 -0.739902) (xy -2.468626 -0.39751)
			)
			(stroke
				(width 0)
				(type default)
			)
			(fill yes)
			(layer "F.SilkS")
		)
		(fp_line
			(start -1.500124 -1.500124)
			(end 1.500124 -1.500124)
			(stroke
				(width 0.1)
				(type default)
			)
			(layer "F.Fab")
		)
		(fp_line
			(start -1.500124 1.500124)
			(end -1.500124 -1.500124)
			(stroke
				(width 0.1)
				(type default)
			)
			(layer "F.Fab")
		)
		(fp_line
			(start 1.500124 -1.500124)
			(end 1.500124 1.500124)
			(stroke
				(width 0.1)
				(type default)
			)
			(layer "F.Fab")
		)
		(fp_line
			(start 1.500124 1.500124)
			(end -1.500124 1.500124)
			(stroke
				(width 0.1)
				(type default)
			)
			(layer "F.Fab")
		)
		(fp_poly
			(pts
				(xy -2.847848 -1.258062) (xy -2.847848 -0.242062) (xy -1.831848 -0.750062)
			)
			(stroke
				(width 0)
				(type default)
			)
			(fill yes)
			(layer "F.Fab")
		)
		(pad "1" smd rect
			(at -1.400048 -0.750062 270)
			(size 0.2286 0.6096)
			(layers "F.Cu" "F.Mask" "F.Paste")
			(net "INA230_2_A1")
		)
		(pad "2" smd rect
			(at -1.400048 -0.249936 270)
			(size 0.2286 0.6096)
			(layers "F.Cu" "F.Mask" "F.Paste")
			(net "INA230_2_A0")
		)
		(pad "3" smd rect
			(at -1.400048 0.249936 270)
			(size 0.2286 0.6096)
			(layers "F.Cu" "F.Mask" "F.Paste")
			(net "E1S_0_P3V3_ADC_ALERT_R")
		)
		(pad "4" smd rect
			(at -1.400048 0.750062 270)
			(size 0.2286 0.6096)
			(layers "F.Cu" "F.Mask" "F.Paste")
			(net "SMB_INA230_2_3V3AUX_SDA_R1")
		)
		(pad "5" smd rect
			(at -0.750062 1.400048)
			(size 0.2286 0.6096)
			(layers "F.Cu" "F.Mask" "F.Paste")
			(net "SMB_INA230_2_3V3AUX_SCL_R1")
		)
		(pad "6" smd rect
			(at -0.249936 1.400048)
			(size 0.2286 0.6096)
			(layers "F.Cu" "F.Mask" "F.Paste")
			(net "NC_INA230_2_NC0")
		)
		(pad "7" smd rect
			(at 0.249936 1.400048)
			(size 0.2286 0.6096)
			(layers "F.Cu" "F.Mask" "F.Paste")
			(net "NC_INA230_2_NC1")
		)
		(pad "8" smd rect
			(at 0.750062 1.400048)
			(size 0.2286 0.6096)
			(layers "F.Cu" "F.Mask" "F.Paste")
			(net "NC_INA230_2_NC2")
		)
		(pad "9" smd rect
			(at 1.400048 0.750062 270)
			(size 0.2286 0.6096)
			(layers "F.Cu" "F.Mask" "F.Paste")
			(net "P3V3_AUX")
		)
		(pad "10" smd rect
			(at 1.400048 0.249936 270)
			(size 0.2286 0.6096)
			(layers "F.Cu" "F.Mask" "F.Paste")
			(net "GND")
		)
		(pad "11" smd rect
			(at 1.400048 -0.249936 270)
			(size 0.2286 0.6096)
			(layers "F.Cu" "F.Mask" "F.Paste")
			(net "P3V3_E1S_0_R")
		)
		(pad "12" smd rect
			(at 1.400048 -0.750062 270)
			(size 0.2286 0.6096)
			(layers "F.Cu" "F.Mask" "F.Paste")
			(net "VSENSE_P3V3_INA230_2_INN")
		)
		(pad "13" smd rect
			(at 0.750062 -1.400048)
			(size 0.2286 0.6096)
			(layers "F.Cu" "F.Mask" "F.Paste")
			(net "VSENSE_P3V3_INA230_2_INP")
		)
		(pad "14" smd rect
			(at 0.249936 -1.400048)
			(size 0.2286 0.6096)
			(layers "F.Cu" "F.Mask" "F.Paste")
			(net "NC_INA230_2_NC3")
		)
		(pad "15" smd rect
			(at -0.249936 -1.400048)
			(size 0.2286 0.6096)
			(layers "F.Cu" "F.Mask" "F.Paste")
			(net "NC_INA230_2_NC4")
		)
		(pad "16" smd rect
			(at -0.750062 -1.400048)
			(size 0.2286 0.6096)
			(layers "F.Cu" "F.Mask" "F.Paste")
			(net "NC_INA230_2_NC5")
		)
		(pad "TH" smd rect
			(at 0 0)
			(size 1.7018 1.7018)
			(layers "F.Cu" "F.Mask" "F.Paste")
			(net "GND")
		)
		(zone
			(layer "F.Cu")
			(hatch none 0.5)
			(connect_pads
				(clearance 0)
			)
			(min_thickness 0.25)
			(keepout
				(tracks not_allowed)
				(vias allowed)
				(pads allowed)
				(copperpour not_allowed)
				(footprints allowed)
			)
			(placement
				(enabled no)
				(sheetname "")
			)
			(fill
				(thermal_gap 0.5)
				(thermal_bridge_width 0.5)
				(island_removal_mode 0)
			)
			(polygon
				(pts
					(xy 214.215218 -54.455314) (xy 214.357966 -54.455314) (xy 214.357966 -53.553614) (xy 216.161366 -53.553614)
					(xy 216.161366 -53.967888) (xy 216.304114 -53.967888) (xy 216.304114 -53.410866) (xy 214.215218 -53.410866)
				)
			)
		)
	)
)
